(kicad_pcb
	(version 20260206)
	(generator "pcbnew")
	(generator_version "10.0")
	(general
		(thickness 1.6)
		(legacy_teardrops no)
	)
	(paper "A4")
	(title_block
		(title "03242023_DA0F0TMBIJ0_F0T_Motherboard_J_brd_V01_OCP.brd")
		(comment 1 "Grand Teton / footprints 2262-2267 of 6105")
	)
	(layers
		(0 "F.Cu" signal "TOP")
		(4 "In1.Cu" signal "GND")
		(6 "In2.Cu" signal "IN1")
		(8 "In3.Cu" signal "GND1")
		(10 "In4.Cu" signal "IN2")
		(12 "In5.Cu" signal "GND2")
		(14 "In6.Cu" signal "IN3")
		(16 "In7.Cu" signal "GND3")
		(18 "In8.Cu" signal "VCC")
		(20 "In9.Cu" signal "VCC1")
		(22 "In10.Cu" signal "GND4")
		(24 "In11.Cu" signal "IN4")
		(26 "In12.Cu" signal "GND5")
		(28 "In13.Cu" signal "IN5")
		(30 "In14.Cu" signal "GND6")
		(32 "In15.Cu" signal "IN6")
		(34 "In16.Cu" signal "GND7")
		(2 "B.Cu" signal "BOTTOM")
		(9 "F.Adhes" user "F.Adhesive")
		(11 "B.Adhes" user "B.Adhesive")
		(13 "F.Paste" user "Package Geometry/Pastemask Top")
		(15 "B.Paste" user "Package Geometry/Pastemask Bottom")
		(5 "F.SilkS" user "Ref Des/Silkscreen Top")
		(7 "B.SilkS" user "Ref Des/Silkscreen Bottom")
		(1 "F.Mask" user "Board Geometry/Soldermask Top")
		(3 "B.Mask" user "Board Geometry/Soldermask Bottom")
		(17 "Dwgs.User" user "User.Drawings")
		(19 "Cmts.User" user "User.Comments")
		(21 "Eco1.User" user "User.Eco1")
		(23 "Eco2.User" user "User.Eco2")
		(25 "Edge.Cuts" user "Board Geometry/Outline")
		(27 "Margin" user)
		(31 "F.CrtYd" user "Package Geometry/Place Bound Top")
		(29 "B.CrtYd" user "Package Geometry/Place Bound Bottom")
		(35 "F.Fab" user "Ref Des/Assembly Top")
		(33 "B.Fab" user "Ref Des/Assembly Bottom")
	)
	(footprint ""
		(layer "F.Cu")
		(at 408.554682 -170.821858 180)
		(property "Reference" "PL4"
			(at 3.264662 3.982212 0)
			(unlocked yes)
			(layer "F.SilkS")
			(effects
				(font
					(size 0.7874 0.5842)
					(thickness 0.1524)
				)
				(justify left)
			)
		)
		(property "Value" ""
			(at 0 0 180)
			(layer "F.Fab")
			(effects
				(font
					(size 1.27 1.27)
				)
			)
		)
		(duplicate_pad_numbers_are_jumpers no)
		(fp_line
			(start 3.24993 3.24993)
			(end -3.24993 3.24993)
			(stroke
				(width 0.1524)
				(type default)
			)
			(layer "F.SilkS")
		)
		(fp_line
			(start 3.24993 2.2352)
			(end 3.24993 3.24993)
			(stroke
				(width 0.1524)
				(type default)
			)
			(layer "F.SilkS")
		)
		(fp_line
			(start 3.24993 -3.24993)
			(end 3.24993 -2.2352)
			(stroke
				(width 0.1524)
				(type default)
			)
			(layer "F.SilkS")
		)
		(fp_line
			(start -3.24993 3.24993)
			(end -3.24993 2.2352)
			(stroke
				(width 0.1524)
				(type default)
			)
			(layer "F.SilkS")
		)
		(fp_line
			(start -3.24993 -2.2352)
			(end -3.24993 -3.24993)
			(stroke
				(width 0.1524)
				(type default)
			)
			(layer "F.SilkS")
		)
		(fp_line
			(start -3.24993 -3.24993)
			(end 3.24993 -3.24993)
			(stroke
				(width 0.1524)
				(type default)
			)
			(layer "F.SilkS")
		)
		(fp_line
			(start 3.24993 3.24993)
			(end -3.24993 3.24993)
			(stroke
				(width 0.1)
				(type default)
			)
			(layer "F.Fab")
		)
		(fp_line
			(start 3.24993 -3.24993)
			(end 3.24993 3.24993)
			(stroke
				(width 0.1)
				(type default)
			)
			(layer "F.Fab")
		)
		(fp_line
			(start -3.24993 3.24993)
			(end -3.24993 -3.24993)
			(stroke
				(width 0.1)
				(type default)
			)
			(layer "F.Fab")
		)
		(fp_line
			(start -3.24993 -3.24993)
			(end 3.24993 -3.24993)
			(stroke
				(width 0.1)
				(type default)
			)
			(layer "F.Fab")
		)
		(pad "1" smd rect
			(at -2.29997 0 180)
			(size 2.0066 4.2164)
			(layers "F.Cu" "F.Mask" "F.Paste")
			(net "SW_PVCCINFAON_CPU0_SW1")
		)
		(pad "2" smd rect
			(at 2.29997 0 180)
			(size 2.0066 4.2164)
			(layers "F.Cu" "F.Mask" "F.Paste")
			(net "PVCCINFAON_CPU0")
		)
	)
	(footprint ""
		(layer "F.Cu")
		(at 73.374758 -402.371052 -90)
		(property "Reference" "C727"
			(at 0 0 270)
			(layer "F.SilkS")
			(hide yes)
			(effects
				(font
					(size 1.27 1.27)
				)
			)
		)
		(property "Value" ""
			(at 0 0 270)
			(layer "F.Fab")
			(effects
				(font
					(size 1.27 1.27)
				)
			)
		)
		(duplicate_pad_numbers_are_jumpers no)
		(fp_line
			(start -0.299974 0.150114)
			(end -0.299974 -0.150114)
			(stroke
				(width 0.1)
				(type default)
			)
			(layer "F.Fab")
		)
		(fp_line
			(start 0.299974 0.150114)
			(end -0.299974 0.150114)
			(stroke
				(width 0.1)
				(type default)
			)
			(layer "F.Fab")
		)
		(fp_line
			(start -0.299974 -0.150114)
			(end 0.299974 -0.150114)
			(stroke
				(width 0.1)
				(type default)
			)
			(layer "F.Fab")
		)
		(fp_line
			(start 0.299974 -0.150114)
			(end 0.299974 0.150114)
			(stroke
				(width 0.1)
				(type default)
			)
			(layer "F.Fab")
		)
		(pad "1" smd rect
			(at -0.2667 0 270)
			(size 0.3048 0.381)
			(layers "F.Cu" "F.Mask" "F.Paste")
			(net "P5E_CPU1_PE0_TX_C_DP<7>")
		)
		(pad "2" smd rect
			(at 0.2667 0 270)
			(size 0.3048 0.381)
			(layers "F.Cu" "F.Mask" "F.Paste")
			(net "P5E_CPU1_PE0_TX_DP<7>")
		)
	)
	(footprint ""
		(layer "F.Cu")
		(at 209.74558 -126.512828)
		(property "Reference" "C1319"
			(at 0 0 0)
			(layer "F.SilkS")
			(hide yes)
			(effects
				(font
					(size 1.27 1.27)
				)
			)
		)
		(property "Value" ""
			(at 0 0 0)
			(layer "F.Fab")
			(effects
				(font
					(size 1.27 1.27)
				)
			)
		)
		(duplicate_pad_numbers_are_jumpers no)
		(fp_line
			(start -0.7874 -0.4064)
			(end 0.7874 -0.4064)
			(stroke
				(width 0.1524)
				(type default)
			)
			(layer "F.SilkS")
		)
		(fp_line
			(start -0.7874 0.4064)
			(end -0.7874 -0.4064)
			(stroke
				(width 0.1524)
				(type default)
			)
			(layer "F.SilkS")
		)
		(fp_line
			(start 0.7874 -0.4064)
			(end 0.7874 0.4064)
			(stroke
				(width 0.1524)
				(type default)
			)
			(layer "F.SilkS")
		)
		(fp_line
			(start 0.7874 0.4064)
			(end -0.7874 0.4064)
			(stroke
				(width 0.1524)
				(type default)
			)
			(layer "F.SilkS")
		)
		(fp_line
			(start -0.67945 -0.305054)
			(end -0.12065 -0.305054)
			(stroke
				(width 0.1)
				(type default)
			)
			(layer "F.Fab")
		)
		(fp_line
			(start -0.67945 0.3048)
			(end -0.67945 -0.305054)
			(stroke
				(width 0.1)
				(type default)
			)
			(layer "F.Fab")
		)
		(fp_line
			(start -0.12065 -0.305054)
			(end -0.12065 -0.2794)
			(stroke
				(width 0.1)
				(type default)
			)
			(layer "F.Fab")
		)
		(fp_line
			(start -0.12065 -0.2794)
			(end 0.12065 -0.2794)
			(stroke
				(width 0.1)
				(type default)
			)
			(layer "F.Fab")
		)
		(fp_line
			(start -0.12065 0.2794)
			(end -0.12065 0.3048)
			(stroke
				(width 0.1)
				(type default)
			)
			(layer "F.Fab")
		)
		(fp_line
			(start -0.12065 0.3048)
			(end -0.67945 0.3048)
			(stroke
				(width 0.1)
				(type default)
			)
			(layer "F.Fab")
		)
		(fp_line
			(start 0.120396 0.2794)
			(end -0.12065 0.2794)
			(stroke
				(width 0.1)
				(type default)
			)
			(layer "F.Fab")
		)
		(fp_line
			(start 0.120396 0.3048)
			(end 0.120396 0.2794)
			(stroke
				(width 0.1)
				(type default)
			)
			(layer "F.Fab")
		)
		(fp_line
			(start 0.12065 -0.3048)
			(end 0.67945 -0.3048)
			(stroke
				(width 0.1)
				(type default)
			)
			(layer "F.Fab")
		)
		(fp_line
			(start 0.12065 -0.2794)
			(end 0.12065 -0.3048)
			(stroke
				(width 0.1)
				(type default)
			)
			(layer "F.Fab")
		)
		(fp_line
			(start 0.67945 -0.3048)
			(end 0.67945 0.3048)
			(stroke
				(width 0.1)
				(type default)
			)
			(layer "F.Fab")
		)
		(fp_line
			(start 0.67945 0.3048)
			(end 0.120396 0.3048)
			(stroke
				(width 0.1)
				(type default)
			)
			(layer "F.Fab")
		)
		(pad "1" smd circle
			(at -0.40005 0)
			(size 0 0)
			(layers "F.Cu" "F.Mask" "F.Paste")
			(net "PWRGD_DSW_PWROK")
		)
		(pad "2" smd circle
			(at 0.40005 0)
			(size 0 0)
			(layers "F.Cu" "F.Mask" "F.Paste")
			(net "GND")
		)
	)
	(footprint ""
		(layer "F.Cu")
		(at 90.397076 -79.078836)
		(property "Reference" "D98"
			(at -45.69841 38.649402 90)
			(unlocked yes)
			(layer "F.SilkS")
			(effects
				(font
					(size 0.635 0.4064)
					(thickness 0.1524)
				)
				(justify left)
			)
		)
		(property "Value" ""
			(at 0 0 0)
			(layer "F.Fab")
			(effects
				(font
					(size 1.27 1.27)
				)
			)
		)
		(duplicate_pad_numbers_are_jumpers no)
		(fp_line
			(start -0.90678 0.4826)
			(end -0.90678 -0.4699)
			(stroke
				(width 0.1524)
				(type default)
			)
			(layer "F.SilkS")
		)
		(fp_line
			(start -0.89408 -0.4826)
			(end 0.90678 -0.4826)
			(stroke
				(width 0.1524)
				(type default)
			)
			(layer "F.SilkS")
		)
		(fp_line
			(start -0.79248 -0.4826)
			(end 1.03378 -0.4826)
			(stroke
				(width 0.1524)
				(type default)
			)
			(layer "F.SilkS")
		)
		(fp_line
			(start -0.64008 -0.4826)
			(end 1.16078 -0.4826)
			(stroke
				(width 0.1524)
				(type default)
			)
			(layer "F.SilkS")
		)
		(fp_line
			(start 0.90678 -0.4826)
			(end 0.90678 0.4826)
			(stroke
				(width 0.1524)
				(type default)
			)
			(layer "F.SilkS")
		)
		(fp_line
			(start 0.90678 0.4826)
			(end -0.90678 0.4826)
			(stroke
				(width 0.1524)
				(type default)
			)
			(layer "F.SilkS")
		)
		(fp_line
			(start 1.03378 -0.4826)
			(end 1.03378 0.4826)
			(stroke
				(width 0.1524)
				(type default)
			)
			(layer "F.SilkS")
		)
		(fp_line
			(start 1.03378 0.4826)
			(end -0.79248 0.4826)
			(stroke
				(width 0.1524)
				(type default)
			)
			(layer "F.SilkS")
		)
		(fp_line
			(start 1.16078 -0.4826)
			(end 1.16078 0.4826)
			(stroke
				(width 0.1524)
				(type default)
			)
			(layer "F.SilkS")
		)
		(fp_line
			(start 1.16078 0.4826)
			(end -0.64008 0.4826)
			(stroke
				(width 0.1524)
				(type default)
			)
			(layer "F.SilkS")
		)
		(fp_line
			(start -0.499872 -0.249936)
			(end 0.499872 -0.249936)
			(stroke
				(width 0.1)
				(type default)
			)
			(layer "F.Fab")
		)
		(fp_line
			(start -0.499872 0.249936)
			(end -0.499872 -0.249936)
			(stroke
				(width 0.1)
				(type default)
			)
			(layer "F.Fab")
		)
		(fp_line
			(start 0.499872 -0.249936)
			(end 0.499872 0.249936)
			(stroke
				(width 0.1)
				(type default)
			)
			(layer "F.Fab")
		)
		(fp_line
			(start 0.499872 0.249936)
			(end -0.499872 0.249936)
			(stroke
				(width 0.1)
				(type default)
			)
			(layer "F.Fab")
		)
		(pad "A" smd rect
			(at -0.47498 0)
			(size 0.6096 0.7112)
			(layers "F.Cu" "F.Mask" "F.Paste")
			(net "LED_P5V")
		)
		(pad "C" smd rect
			(at 0.47498 0)
			(size 0.6096 0.7112)
			(layers "F.Cu" "F.Mask" "F.Paste")
			(net "GND")
		)
	)
	(footprint ""
		(layer "F.Cu")
		(at 377.668536 -99.133152 -90)
		(property "Reference" "U83"
			(at -1.032002 -3.3909 0)
			(unlocked yes)
			(layer "F.SilkS")
			(effects
				(font
					(size 0.7874 0.5842)
					(thickness 0.1524)
				)
				(justify left)
			)
		)
		(property "Value" ""
			(at 0 0 270)
			(layer "F.Fab")
			(effects
				(font
					(size 1.27 1.27)
				)
			)
		)
		(duplicate_pad_numbers_are_jumpers no)
		(fp_line
			(start -2.0066 2.5527)
			(end -2.0066 -2.5527)
			(stroke
				(width 0.1524)
				(type default)
			)
			(layer "F.SilkS")
		)
		(fp_line
			(start 2.0066 2.5527)
			(end -2.0066 2.5527)
			(stroke
				(width 0.1524)
				(type default)
			)
			(layer "F.SilkS")
		)
		(fp_line
			(start 0 -1.9812)
			(end 0.5715 -2.5527)
			(stroke
				(width 0.1524)
				(type default)
			)
			(layer "F.SilkS")
		)
		(fp_line
			(start -2.0066 -2.5527)
			(end -0.5715 -2.5527)
			(stroke
				(width 0.1524)
				(type default)
			)
			(layer "F.SilkS")
		)
		(fp_line
			(start -0.5715 -2.5527)
			(end 0 -1.9812)
			(stroke
				(width 0.1524)
				(type default)
			)
			(layer "F.SilkS")
		)
		(fp_line
			(start 0.5715 -2.5527)
			(end 2.0066 -2.5527)
			(stroke
				(width 0.1524)
				(type default)
			)
			(layer "F.SilkS")
		)
		(fp_line
			(start 2.0066 -2.5527)
			(end 2.0066 2.5527)
			(stroke
				(width 0.1524)
				(type default)
			)
			(layer "F.SilkS")
		)
		(fp_poly
			(pts
				(xy -2.712212 -2.987548) (xy -3.04038 -2.433828) (xy -3.337052 -2.987548)
			)
			(stroke
				(width 0)
				(type default)
			)
			(fill yes)
			(layer "F.SilkS")
		)
		(fp_line
			(start -2.249932 2.549906)
			(end -2.249932 -2.549906)
			(stroke
				(width 0.1)
				(type default)
			)
			(layer "F.Fab")
		)
		(fp_line
			(start 2.249932 2.549906)
			(end -2.249932 2.549906)
			(stroke
				(width 0.1)
				(type default)
			)
			(layer "F.Fab")
		)
		(fp_line
			(start -2.249932 -2.549906)
			(end 2.249932 -2.549906)
			(stroke
				(width 0.1)
				(type default)
			)
			(layer "F.Fab")
		)
		(fp_line
			(start 2.249932 -2.549906)
			(end 2.249932 2.549906)
			(stroke
				(width 0.1)
				(type default)
			)
			(layer "F.Fab")
		)
		(fp_poly
			(pts
				(xy -4.36372 -1.608328) (xy -4.36372 -2.233168) (xy -3.81 -1.905)
			)
			(stroke
				(width 0)
				(type default)
			)
			(fill yes)
			(layer "F.Fab")
		)
		(pad "1" smd rect
			(at -2.921 -1.949958 180)
			(size 0.3556 1.4986)
			(layers "F.Cu" "F.Mask" "F.Paste")
			(net "PD_GTL2014_BMC_JTAG_DIR_2")
		)
		(pad "2" smd rect
			(at -2.921 -1.299972 180)
			(size 0.3556 1.4986)
			(layers "F.Cu" "F.Mask" "F.Paste")
			(net "PD_JTAG_DBP_B0")
		)
		(pad "3" smd rect
			(at -2.921 -0.649986 180)
			(size 0.3556 1.4986)
			(layers "F.Cu" "F.Mask" "F.Paste")
			(net "JTAG_DBP_PRDY_R_N")
		)
		(pad "4" smd rect
			(at -2.921 0 180)
			(size 0.3556 1.4986)
			(layers "F.Cu" "F.Mask" "F.Paste")
			(net "P0V7_JTAG_VREF_2")
		)
		(pad "5" smd rect
			(at -2.921 0.649986 180)
			(size 0.3556 1.4986)
			(layers "F.Cu" "F.Mask" "F.Paste")
			(net "PD_JTAG_DBP_B2")
		)
		(pad "6" smd rect
			(at -2.921 1.299972 180)
			(size 0.3556 1.4986)
			(layers "F.Cu" "F.Mask" "F.Paste")
			(net "JTAG_DBP_FB_TDO")
		)
		(pad "7" smd rect
			(at -2.921 1.949958 180)
			(size 0.3556 1.4986)
			(layers "F.Cu" "F.Mask" "F.Paste")
			(net "GND")
		)
		(pad "8" smd rect
			(at 2.921 1.949958 180)
			(size 0.3556 1.4986)
			(layers "F.Cu" "F.Mask" "F.Paste")
			(net "GND")
		)
		(pad "9" smd rect
			(at 2.921 1.299972 180)
			(size 0.3556 1.4986)
			(layers "F.Cu" "F.Mask" "F.Paste")
			(net "JTAG_BMC_DBP_TDO_R")
		)
		(pad "10" smd rect
			(at 2.921 0.649986 180)
			(size 0.3556 1.4986)
			(layers "F.Cu" "F.Mask" "F.Paste")
			(net "TP_JTAG_BMC_A2")
		)
		(pad "11" smd rect
			(at 2.921 0 180)
			(size 0.3556 1.4986)
			(layers "F.Cu" "F.Mask" "F.Paste")
			(net "GND")
		)
		(pad "12" smd rect
			(at 2.921 -0.649986 180)
			(size 0.3556 1.4986)
			(layers "F.Cu" "F.Mask" "F.Paste")
			(net "JTAG_DBP_BMC_PRDY_R1_N")
		)
		(pad "13" smd rect
			(at 2.921 -1.299972 180)
			(size 0.3556 1.4986)
			(layers "F.Cu" "F.Mask" "F.Paste")
			(net "TP_JTAG_BMC_A0")
		)
		(pad "14" smd rect
			(at 2.921 -1.949958 180)
			(size 0.3556 1.4986)
			(layers "F.Cu" "F.Mask" "F.Paste")
			(net "P3V3_AUX")
		)
	)
	(footprint ""
		(layer "F.Cu")
		(at 432.74488 -128.361948 90)
		(property "Reference" "PR4230"
			(at 0 0 90)
			(layer "F.SilkS")
			(hide yes)
			(effects
				(font
					(size 1.27 1.27)
				)
			)
		)
		(property "Value" ""
			(at 0 0 90)
			(layer "F.Fab")
			(effects
				(font
					(size 1.27 1.27)
				)
			)
		)
		(duplicate_pad_numbers_are_jumpers no)
		(fp_line
			(start 0.7874 -0.4064)
			(end 0.7874 0.4064)
			(stroke
				(width 0.1524)
				(type default)
			)
			(layer "F.SilkS")
		)
		(fp_line
			(start -0.7874 -0.4064)
			(end 0.7874 -0.4064)
			(stroke
				(width 0.1524)
				(type default)
			)
			(layer "F.SilkS")
		)
		(fp_line
			(start 0.7874 0.4064)
			(end -0.7874 0.4064)
			(stroke
				(width 0.1524)
				(type default)
			)
			(layer "F.SilkS")
		)
		(fp_line
			(start -0.7874 0.4064)
			(end -0.7874 -0.4064)
			(stroke
				(width 0.1524)
				(type default)
			)
			(layer "F.SilkS")
		)
		(fp_line
			(start -0.12065 -0.305054)
			(end -0.12065 -0.2794)
			(stroke
				(width 0.1)
				(type default)
			)
			(layer "F.Fab")
		)
		(fp_line
			(start -0.67945 -0.305054)
			(end -0.12065 -0.305054)
			(stroke
				(width 0.1)
				(type default)
			)
			(layer "F.Fab")
		)
		(fp_line
			(start 0.67945 -0.3048)
			(end 0.67945 0.3048)
			(stroke
				(width 0.1)
				(type default)
			)
			(layer "F.Fab")
		)
		(fp_line
			(start 0.12065 -0.3048)
			(end 0.67945 -0.3048)
			(stroke
				(width 0.1)
				(type default)
			)
			(layer "F.Fab")
		)
		(fp_line
			(start 0.12065 -0.2794)
			(end 0.12065 -0.3048)
			(stroke
				(width 0.1)
				(type default)
			)
			(layer "F.Fab")
		)
		(fp_line
			(start -0.12065 -0.2794)
			(end 0.12065 -0.2794)
			(stroke
				(width 0.1)
				(type default)
			)
			(layer "F.Fab")
		)
		(fp_line
			(start 0.120396 0.2794)
			(end -0.12065 0.2794)
			(stroke
				(width 0.1)
				(type default)
			)
			(layer "F.Fab")
		)
		(fp_line
			(start -0.12065 0.2794)
			(end -0.12065 0.3048)
			(stroke
				(width 0.1)
				(type default)
			)
			(layer "F.Fab")
		)
		(fp_line
			(start 0.67945 0.3048)
			(end 0.120396 0.3048)
			(stroke
				(width 0.1)
				(type default)
			)
			(layer "F.Fab")
		)
		(fp_line
			(start 0.120396 0.3048)
			(end 0.120396 0.2794)
			(stroke
				(width 0.1)
				(type default)
			)
			(layer "F.Fab")
		)
		(fp_line
			(start -0.12065 0.3048)
			(end -0.67945 0.3048)
			(stroke
				(width 0.1)
				(type default)
			)
			(layer "F.Fab")
		)
		(fp_line
			(start -0.67945 0.3048)
			(end -0.67945 -0.305054)
			(stroke
				(width 0.1)
				(type default)
			)
			(layer "F.Fab")
		)
		(pad "1" smd circle
			(at -0.40005 0 90)
			(size 0 0)
			(layers "F.Cu" "F.Mask" "F.Paste")
			(net "NC_PVCCD_HV_CPU0_ACSP2")
		)
		(pad "2" smd circle
			(at 0.40005 0 90)
			(size 0 0)
			(layers "F.Cu" "F.Mask" "F.Paste")
			(net "GND")
		)
	)
)
